(kicad_pcb
	(version 20260206)
	(generator "pcbnew")
	(generator_version "10.0")
	(general
		(thickness 1.6)
		(legacy_teardrops no)
	)
	(paper "A4")
	(title_block
		(title "04192023_DAF0TMB3IC0_F0TG_MB_C_brd_V02_OCP.brd")
		(comment 1 "Grand Teton / footprints 6895-6901 of 8354")
	)
	(layers
		(0 "F.Cu" signal "TOP")
		(4 "In1.Cu" signal "GND")
		(6 "In2.Cu" signal "IN1")
		(8 "In3.Cu" signal "GND1")
		(10 "In4.Cu" signal "IN2")
		(12 "In5.Cu" signal "GND2")
		(14 "In6.Cu" signal "IN3")
		(16 "In7.Cu" signal "GND3")
		(18 "In8.Cu" signal "VCC")
		(20 "In9.Cu" signal "VCC1")
		(22 "In10.Cu" signal "GND4")
		(24 "In11.Cu" signal "IN4")
		(26 "In12.Cu" signal "GND5")
		(28 "In13.Cu" signal "IN5")
		(30 "In14.Cu" signal "GND6")
		(32 "In15.Cu" signal "IN6")
		(34 "In16.Cu" signal "GND7")
		(2 "B.Cu" signal "BOTTOM")
		(9 "F.Adhes" user "F.Adhesive")
		(11 "B.Adhes" user "B.Adhesive")
		(13 "F.Paste" user "Package Geometry/Pastemask Top")
		(15 "B.Paste" user "Package Geometry/Pastemask Bottom")
		(5 "F.SilkS" user "Ref Des/Silkscreen Top")
		(7 "B.SilkS" user "Ref Des/Silkscreen Bottom")
		(1 "F.Mask" user "Board Geometry/Soldermask Top")
		(3 "B.Mask" user "Board Geometry/Soldermask Bottom")
		(17 "Dwgs.User" user "User.Drawings")
		(19 "Cmts.User" user "User.Comments")
		(21 "Eco1.User" user "User.Eco1")
		(23 "Eco2.User" user "User.Eco2")
		(25 "Edge.Cuts" user "Board Geometry/Outline")
		(27 "Margin" user)
		(31 "F.CrtYd" user "Package Geometry/Place Bound Top")
		(29 "B.CrtYd" user "Package Geometry/Place Bound Bottom")
		(35 "F.Fab" user "Ref Des/Assembly Top")
		(33 "B.Fab" user "Ref Des/Assembly Bottom")
	)
	(footprint ""
		(layer "B.Cu")
		(at 393.440158 -327.644252)
		(property "Reference" "R460"
			(at 0 0 0)
			(layer "B.SilkS")
			(hide yes)
			(effects
				(font
					(size 1.27 1.27)
				)
				(justify mirror)
			)
		)
		(property "Value" ""
			(at 0 0 0)
			(layer "B.Fab")
			(effects
				(font
					(size 1.27 1.27)
				)
				(justify mirror)
			)
		)
		(duplicate_pad_numbers_are_jumpers no)
		(fp_line
			(start -0.7874 -0.4064)
			(end -0.7874 0.4064)
			(stroke
				(width 0.1524)
				(type default)
			)
			(layer "B.SilkS")
		)
		(fp_line
			(start -0.7874 0.4064)
			(end 0.7874 0.4064)
			(stroke
				(width 0.1524)
				(type default)
			)
			(layer "B.SilkS")
		)
		(fp_line
			(start 0.7874 -0.4064)
			(end -0.7874 -0.4064)
			(stroke
				(width 0.1524)
				(type default)
			)
			(layer "B.SilkS")
		)
		(fp_line
			(start 0.7874 0.4064)
			(end 0.7874 -0.4064)
			(stroke
				(width 0.1524)
				(type default)
			)
			(layer "B.SilkS")
		)
		(fp_line
			(start -0.67945 -0.3048)
			(end -0.67945 0.3048)
			(stroke
				(width 0.1)
				(type default)
			)
			(layer "B.Fab")
		)
		(fp_line
			(start -0.67945 0.3048)
			(end -0.120396 0.3048)
			(stroke
				(width 0.1)
				(type default)
			)
			(layer "B.Fab")
		)
		(fp_line
			(start -0.12065 -0.3048)
			(end -0.67945 -0.3048)
			(stroke
				(width 0.1)
				(type default)
			)
			(layer "B.Fab")
		)
		(fp_line
			(start -0.12065 -0.2794)
			(end -0.12065 -0.3048)
			(stroke
				(width 0.1)
				(type default)
			)
			(layer "B.Fab")
		)
		(fp_line
			(start -0.120396 0.2794)
			(end 0.12065 0.2794)
			(stroke
				(width 0.1)
				(type default)
			)
			(layer "B.Fab")
		)
		(fp_line
			(start -0.120396 0.3048)
			(end -0.120396 0.2794)
			(stroke
				(width 0.1)
				(type default)
			)
			(layer "B.Fab")
		)
		(fp_line
			(start 0.12065 -0.305054)
			(end 0.12065 -0.2794)
			(stroke
				(width 0.1)
				(type default)
			)
			(layer "B.Fab")
		)
		(fp_line
			(start 0.12065 -0.2794)
			(end -0.12065 -0.2794)
			(stroke
				(width 0.1)
				(type default)
			)
			(layer "B.Fab")
		)
		(fp_line
			(start 0.12065 0.2794)
			(end 0.12065 0.3048)
			(stroke
				(width 0.1)
				(type default)
			)
			(layer "B.Fab")
		)
		(fp_line
			(start 0.12065 0.3048)
			(end 0.67945 0.3048)
			(stroke
				(width 0.1)
				(type default)
			)
			(layer "B.Fab")
		)
		(fp_line
			(start 0.67945 -0.305054)
			(end 0.12065 -0.305054)
			(stroke
				(width 0.1)
				(type default)
			)
			(layer "B.Fab")
		)
		(fp_line
			(start 0.67945 0.3048)
			(end 0.67945 -0.305054)
			(stroke
				(width 0.1)
				(type default)
			)
			(layer "B.Fab")
		)
		(pad "1" smd circle
			(at 0.40005 0 180)
			(size 0 0)
			(layers "B.Cu" "B.Mask" "B.Paste")
			(net "SPI_CPU0_CS1_N")
		)
		(pad "2" smd circle
			(at -0.40005 0 180)
			(size 0 0)
			(layers "B.Cu" "B.Mask" "B.Paste")
			(net "SPI_CPU0_R_CS1_N")
		)
	)
	(footprint ""
		(layer "B.Cu")
		(at 109.550454 -30.533086 180)
		(property "Reference" "C6121"
			(at 0 0 0)
			(layer "B.SilkS")
			(hide yes)
			(effects
				(font
					(size 1.27 1.27)
				)
				(justify mirror)
			)
		)
		(property "Value" ""
			(at 0 0 0)
			(layer "B.Fab")
			(effects
				(font
					(size 1.27 1.27)
				)
				(justify mirror)
			)
		)
		(duplicate_pad_numbers_are_jumpers no)
		(fp_line
			(start 0.7874 0.4064)
			(end 0.7874 -0.4064)
			(stroke
				(width 0.1524)
				(type default)
			)
			(layer "B.SilkS")
		)
		(fp_line
			(start 0.7874 -0.4064)
			(end -0.7874 -0.4064)
			(stroke
				(width 0.1524)
				(type default)
			)
			(layer "B.SilkS")
		)
		(fp_line
			(start -0.7874 0.4064)
			(end 0.7874 0.4064)
			(stroke
				(width 0.1524)
				(type default)
			)
			(layer "B.SilkS")
		)
		(fp_line
			(start -0.7874 -0.4064)
			(end -0.7874 0.4064)
			(stroke
				(width 0.1524)
				(type default)
			)
			(layer "B.SilkS")
		)
		(fp_line
			(start 0.67945 0.3048)
			(end 0.67945 -0.305054)
			(stroke
				(width 0.1)
				(type default)
			)
			(layer "B.Fab")
		)
		(fp_line
			(start 0.67945 -0.305054)
			(end 0.12065 -0.305054)
			(stroke
				(width 0.1)
				(type default)
			)
			(layer "B.Fab")
		)
		(fp_line
			(start 0.12065 0.3048)
			(end 0.67945 0.3048)
			(stroke
				(width 0.1)
				(type default)
			)
			(layer "B.Fab")
		)
		(fp_line
			(start 0.12065 0.2794)
			(end 0.12065 0.3048)
			(stroke
				(width 0.1)
				(type default)
			)
			(layer "B.Fab")
		)
		(fp_line
			(start 0.12065 -0.2794)
			(end -0.12065 -0.2794)
			(stroke
				(width 0.1)
				(type default)
			)
			(layer "B.Fab")
		)
		(fp_line
			(start 0.12065 -0.305054)
			(end 0.12065 -0.2794)
			(stroke
				(width 0.1)
				(type default)
			)
			(layer "B.Fab")
		)
		(fp_line
			(start -0.120396 0.3048)
			(end -0.120396 0.2794)
			(stroke
				(width 0.1)
				(type default)
			)
			(layer "B.Fab")
		)
		(fp_line
			(start -0.120396 0.2794)
			(end 0.12065 0.2794)
			(stroke
				(width 0.1)
				(type default)
			)
			(layer "B.Fab")
		)
		(fp_line
			(start -0.12065 -0.2794)
			(end -0.12065 -0.3048)
			(stroke
				(width 0.1)
				(type default)
			)
			(layer "B.Fab")
		)
		(fp_line
			(start -0.12065 -0.3048)
			(end -0.67945 -0.3048)
			(stroke
				(width 0.1)
				(type default)
			)
			(layer "B.Fab")
		)
		(fp_line
			(start -0.67945 0.3048)
			(end -0.120396 0.3048)
			(stroke
				(width 0.1)
				(type default)
			)
			(layer "B.Fab")
		)
		(fp_line
			(start -0.67945 -0.3048)
			(end -0.67945 0.3048)
			(stroke
				(width 0.1)
				(type default)
			)
			(layer "B.Fab")
		)
		(pad "1" smd circle
			(at 0.40005 0)
			(size 0 0)
			(layers "B.Cu" "B.Mask" "B.Paste")
			(net "P1V2_CPU0_USB2_DVDD12")
		)
		(pad "2" smd circle
			(at -0.40005 0)
			(size 0 0)
			(layers "B.Cu" "B.Mask" "B.Paste")
			(net "GND")
		)
	)
	(footprint ""
		(layer "B.Cu")
		(at 107.355386 -269.307564 180)
		(property "Reference" "C2402"
			(at 0 0 0)
			(layer "B.SilkS")
			(hide yes)
			(effects
				(font
					(size 1.27 1.27)
				)
				(justify mirror)
			)
		)
		(property "Value" ""
			(at 0 0 0)
			(layer "B.Fab")
			(effects
				(font
					(size 1.27 1.27)
				)
				(justify mirror)
			)
		)
		(duplicate_pad_numbers_are_jumpers no)
		(fp_line
			(start 0.7874 0.4064)
			(end 0.7874 -0.4064)
			(stroke
				(width 0.1524)
				(type default)
			)
			(layer "B.SilkS")
		)
		(fp_line
			(start 0.7874 -0.4064)
			(end -0.7874 -0.4064)
			(stroke
				(width 0.1524)
				(type default)
			)
			(layer "B.SilkS")
		)
		(fp_line
			(start -0.7874 0.4064)
			(end 0.7874 0.4064)
			(stroke
				(width 0.1524)
				(type default)
			)
			(layer "B.SilkS")
		)
		(fp_line
			(start -0.7874 -0.4064)
			(end -0.7874 0.4064)
			(stroke
				(width 0.1524)
				(type default)
			)
			(layer "B.SilkS")
		)
		(fp_line
			(start 0.67945 0.3048)
			(end 0.67945 -0.305054)
			(stroke
				(width 0.1)
				(type default)
			)
			(layer "B.Fab")
		)
		(fp_line
			(start 0.67945 -0.305054)
			(end 0.12065 -0.305054)
			(stroke
				(width 0.1)
				(type default)
			)
			(layer "B.Fab")
		)
		(fp_line
			(start 0.12065 0.3048)
			(end 0.67945 0.3048)
			(stroke
				(width 0.1)
				(type default)
			)
			(layer "B.Fab")
		)
		(fp_line
			(start 0.12065 0.2794)
			(end 0.12065 0.3048)
			(stroke
				(width 0.1)
				(type default)
			)
			(layer "B.Fab")
		)
		(fp_line
			(start 0.12065 -0.2794)
			(end -0.12065 -0.2794)
			(stroke
				(width 0.1)
				(type default)
			)
			(layer "B.Fab")
		)
		(fp_line
			(start 0.12065 -0.305054)
			(end 0.12065 -0.2794)
			(stroke
				(width 0.1)
				(type default)
			)
			(layer "B.Fab")
		)
		(fp_line
			(start -0.120396 0.3048)
			(end -0.120396 0.2794)
			(stroke
				(width 0.1)
				(type default)
			)
			(layer "B.Fab")
		)
		(fp_line
			(start -0.120396 0.2794)
			(end 0.12065 0.2794)
			(stroke
				(width 0.1)
				(type default)
			)
			(layer "B.Fab")
		)
		(fp_line
			(start -0.12065 -0.2794)
			(end -0.12065 -0.3048)
			(stroke
				(width 0.1)
				(type default)
			)
			(layer "B.Fab")
		)
		(fp_line
			(start -0.12065 -0.3048)
			(end -0.67945 -0.3048)
			(stroke
				(width 0.1)
				(type default)
			)
			(layer "B.Fab")
		)
		(fp_line
			(start -0.67945 0.3048)
			(end -0.120396 0.3048)
			(stroke
				(width 0.1)
				(type default)
			)
			(layer "B.Fab")
		)
		(fp_line
			(start -0.67945 -0.3048)
			(end -0.67945 0.3048)
			(stroke
				(width 0.1)
				(type default)
			)
			(layer "B.Fab")
		)
		(pad "1" smd circle
			(at 0.40005 0)
			(size 0 0)
			(layers "B.Cu" "B.Mask" "B.Paste")
			(net "PVDDCR_CPU1_P1")
		)
		(pad "2" smd circle
			(at -0.40005 0)
			(size 0 0)
			(layers "B.Cu" "B.Mask" "B.Paste")
			(net "GND")
		)
	)
	(footprint ""
		(layer "B.Cu")
		(at 140.906246 -408.517344 90)
		(property "Reference" "C6742"
			(at 0 0 90)
			(layer "B.SilkS")
			(hide yes)
			(effects
				(font
					(size 1.27 1.27)
				)
				(justify mirror)
			)
		)
		(property "Value" ""
			(at 0 0 90)
			(layer "B.Fab")
			(effects
				(font
					(size 1.27 1.27)
				)
				(justify mirror)
			)
		)
		(duplicate_pad_numbers_are_jumpers no)
		(fp_line
			(start 0.299974 -0.150114)
			(end -0.299974 -0.150114)
			(stroke
				(width 0.1)
				(type default)
			)
			(layer "B.Fab")
		)
		(fp_line
			(start -0.299974 -0.150114)
			(end -0.299974 0.150114)
			(stroke
				(width 0.1)
				(type default)
			)
			(layer "B.Fab")
		)
		(fp_line
			(start 0.299974 0.150114)
			(end 0.299974 -0.150114)
			(stroke
				(width 0.1)
				(type default)
			)
			(layer "B.Fab")
		)
		(fp_line
			(start -0.299974 0.150114)
			(end 0.299974 0.150114)
			(stroke
				(width 0.1)
				(type default)
			)
			(layer "B.Fab")
		)
		(pad "1" smd rect
			(at 0.2667 0 270)
			(size 0.3048 0.381)
			(layers "B.Cu" "B.Mask" "B.Paste")
			(net "P5E_CPU1_P3_TX_BUF_C_DN<8>")
		)
		(pad "2" smd rect
			(at -0.2667 0 270)
			(size 0.3048 0.381)
			(layers "B.Cu" "B.Mask" "B.Paste")
			(net "P5E_CPU1_P3_TX_BUF_DN<8>")
		)
	)
	(footprint ""
		(layer "B.Cu")
		(at 203.33208 -36.642548 180)
		(property "Reference" "R3578"
			(at 0 0 0)
			(layer "B.SilkS")
			(hide yes)
			(effects
				(font
					(size 1.27 1.27)
				)
				(justify mirror)
			)
		)
		(property "Value" ""
			(at 0 0 0)
			(layer "B.Fab")
			(effects
				(font
					(size 1.27 1.27)
				)
				(justify mirror)
			)
		)
		(duplicate_pad_numbers_are_jumpers no)
		(fp_line
			(start 0.7874 0.4064)
			(end 0.7874 -0.4064)
			(stroke
				(width 0.1524)
				(type default)
			)
			(layer "B.SilkS")
		)
		(fp_line
			(start 0.7874 -0.4064)
			(end -0.7874 -0.4064)
			(stroke
				(width 0.1524)
				(type default)
			)
			(layer "B.SilkS")
		)
		(fp_line
			(start -0.7874 0.4064)
			(end 0.7874 0.4064)
			(stroke
				(width 0.1524)
				(type default)
			)
			(layer "B.SilkS")
		)
		(fp_line
			(start -0.7874 -0.4064)
			(end -0.7874 0.4064)
			(stroke
				(width 0.1524)
				(type default)
			)
			(layer "B.SilkS")
		)
		(fp_line
			(start 0.67945 0.3048)
			(end 0.67945 -0.305054)
			(stroke
				(width 0.1)
				(type default)
			)
			(layer "B.Fab")
		)
		(fp_line
			(start 0.67945 -0.305054)
			(end 0.12065 -0.305054)
			(stroke
				(width 0.1)
				(type default)
			)
			(layer "B.Fab")
		)
		(fp_line
			(start 0.12065 0.3048)
			(end 0.67945 0.3048)
			(stroke
				(width 0.1)
				(type default)
			)
			(layer "B.Fab")
		)
		(fp_line
			(start 0.12065 0.2794)
			(end 0.12065 0.3048)
			(stroke
				(width 0.1)
				(type default)
			)
			(layer "B.Fab")
		)
		(fp_line
			(start 0.12065 -0.2794)
			(end -0.12065 -0.2794)
			(stroke
				(width 0.1)
				(type default)
			)
			(layer "B.Fab")
		)
		(fp_line
			(start 0.12065 -0.305054)
			(end 0.12065 -0.2794)
			(stroke
				(width 0.1)
				(type default)
			)
			(layer "B.Fab")
		)
		(fp_line
			(start -0.120396 0.3048)
			(end -0.120396 0.2794)
			(stroke
				(width 0.1)
				(type default)
			)
			(layer "B.Fab")
		)
		(fp_line
			(start -0.120396 0.2794)
			(end 0.12065 0.2794)
			(stroke
				(width 0.1)
				(type default)
			)
			(layer "B.Fab")
		)
		(fp_line
			(start -0.12065 -0.2794)
			(end -0.12065 -0.3048)
			(stroke
				(width 0.1)
				(type default)
			)
			(layer "B.Fab")
		)
		(fp_line
			(start -0.12065 -0.3048)
			(end -0.67945 -0.3048)
			(stroke
				(width 0.1)
				(type default)
			)
			(layer "B.Fab")
		)
		(fp_line
			(start -0.67945 0.3048)
			(end -0.120396 0.3048)
			(stroke
				(width 0.1)
				(type default)
			)
			(layer "B.Fab")
		)
		(fp_line
			(start -0.67945 -0.3048)
			(end -0.67945 0.3048)
			(stroke
				(width 0.1)
				(type default)
			)
			(layer "B.Fab")
		)
		(pad "1" smd circle
			(at 0.40005 0)
			(size 0 0)
			(layers "B.Cu" "B.Mask" "B.Paste")
			(net "P12V_SCM_R")
		)
		(pad "2" smd circle
			(at -0.40005 0)
			(size 0 0)
			(layers "B.Cu" "B.Mask" "B.Paste")
			(net "VSENSE_P12V_INA230_5_INP")
		)
	)
	(footprint ""
		(layer "B.Cu")
		(at 162.46983 -16.77416 180)
		(property "Reference" "R4151"
			(at 0 0 0)
			(layer "B.SilkS")
			(hide yes)
			(effects
				(font
					(size 1.27 1.27)
				)
				(justify mirror)
			)
		)
		(property "Value" ""
			(at 0 0 0)
			(layer "B.Fab")
			(effects
				(font
					(size 1.27 1.27)
				)
				(justify mirror)
			)
		)
		(duplicate_pad_numbers_are_jumpers no)
		(fp_line
			(start 0.7874 0.4064)
			(end 0.7874 -0.4064)
			(stroke
				(width 0.1524)
				(type default)
			)
			(layer "B.SilkS")
		)
		(fp_line
			(start 0.7874 -0.4064)
			(end -0.7874 -0.4064)
			(stroke
				(width 0.1524)
				(type default)
			)
			(layer "B.SilkS")
		)
		(fp_line
			(start -0.7874 0.4064)
			(end 0.7874 0.4064)
			(stroke
				(width 0.1524)
				(type default)
			)
			(layer "B.SilkS")
		)
		(fp_line
			(start -0.7874 -0.4064)
			(end -0.7874 0.4064)
			(stroke
				(width 0.1524)
				(type default)
			)
			(layer "B.SilkS")
		)
		(fp_line
			(start 0.67945 0.3048)
			(end 0.67945 -0.305054)
			(stroke
				(width 0.1)
				(type default)
			)
			(layer "B.Fab")
		)
		(fp_line
			(start 0.67945 -0.305054)
			(end 0.12065 -0.305054)
			(stroke
				(width 0.1)
				(type default)
			)
			(layer "B.Fab")
		)
		(fp_line
			(start 0.12065 0.3048)
			(end 0.67945 0.3048)
			(stroke
				(width 0.1)
				(type default)
			)
			(layer "B.Fab")
		)
		(fp_line
			(start 0.12065 0.2794)
			(end 0.12065 0.3048)
			(stroke
				(width 0.1)
				(type default)
			)
			(layer "B.Fab")
		)
		(fp_line
			(start 0.12065 -0.2794)
			(end -0.12065 -0.2794)
			(stroke
				(width 0.1)
				(type default)
			)
			(layer "B.Fab")
		)
		(fp_line
			(start 0.12065 -0.305054)
			(end 0.12065 -0.2794)
			(stroke
				(width 0.1)
				(type default)
			)
			(layer "B.Fab")
		)
		(fp_line
			(start -0.120396 0.3048)
			(end -0.120396 0.2794)
			(stroke
				(width 0.1)
				(type default)
			)
			(layer "B.Fab")
		)
		(fp_line
			(start -0.120396 0.2794)
			(end 0.12065 0.2794)
			(stroke
				(width 0.1)
				(type default)
			)
			(layer "B.Fab")
		)
		(fp_line
			(start -0.12065 -0.2794)
			(end -0.12065 -0.3048)
			(stroke
				(width 0.1)
				(type default)
			)
			(layer "B.Fab")
		)
		(fp_line
			(start -0.12065 -0.3048)
			(end -0.67945 -0.3048)
			(stroke
				(width 0.1)
				(type default)
			)
			(layer "B.Fab")
		)
		(fp_line
			(start -0.67945 0.3048)
			(end -0.120396 0.3048)
			(stroke
				(width 0.1)
				(type default)
			)
			(layer "B.Fab")
		)
		(fp_line
			(start -0.67945 -0.3048)
			(end -0.67945 0.3048)
			(stroke
				(width 0.1)
				(type default)
			)
			(layer "B.Fab")
		)
		(pad "1" smd circle
			(at 0.40005 0)
			(size 0 0)
			(layers "B.Cu" "B.Mask" "B.Paste")
			(net "SMB_1_PLD_3V3AUX_SCL")
		)
		(pad "2" smd circle
			(at -0.40005 0)
			(size 0 0)
			(layers "B.Cu" "B.Mask" "B.Paste")
			(net "SMB_2_PLD_3V3AUX_SCL_R1")
		)
	)
	(footprint ""
		(layer "B.Cu")
		(at 185.458608 -111.466376 -90)
		(property "Reference" "R1189"
			(at 0 0 90)
			(layer "B.SilkS")
			(hide yes)
			(effects
				(font
					(size 1.27 1.27)
				)
				(justify mirror)
			)
		)
		(property "Value" ""
			(at 0 0 90)
			(layer "B.Fab")
			(effects
				(font
					(size 1.27 1.27)
				)
				(justify mirror)
			)
		)
		(duplicate_pad_numbers_are_jumpers no)
		(fp_line
			(start -0.7874 0.4064)
			(end 0.7874 0.4064)
			(stroke
				(width 0.1524)
				(type default)
			)
			(layer "B.SilkS")
		)
		(fp_line
			(start 0.7874 0.4064)
			(end 0.7874 -0.4064)
			(stroke
				(width 0.1524)
				(type default)
			)
			(layer "B.SilkS")
		)
		(fp_line
			(start -0.7874 -0.4064)
			(end -0.7874 0.4064)
			(stroke
				(width 0.1524)
				(type default)
			)
			(layer "B.SilkS")
		)
		(fp_line
			(start 0.7874 -0.4064)
			(end -0.7874 -0.4064)
			(stroke
				(width 0.1524)
				(type default)
			)
			(layer "B.SilkS")
		)
		(fp_line
			(start -0.67945 0.3048)
			(end -0.120396 0.3048)
			(stroke
				(width 0.1)
				(type default)
			)
			(layer "B.Fab")
		)
		(fp_line
			(start -0.120396 0.3048)
			(end -0.120396 0.2794)
			(stroke
				(width 0.1)
				(type default)
			)
			(layer "B.Fab")
		)
		(fp_line
			(start 0.12065 0.3048)
			(end 0.67945 0.3048)
			(stroke
				(width 0.1)
				(type default)
			)
			(layer "B.Fab")
		)
		(fp_line
			(start 0.67945 0.3048)
			(end 0.67945 -0.305054)
			(stroke
				(width 0.1)
				(type default)
			)
			(layer "B.Fab")
		)
		(fp_line
			(start -0.120396 0.2794)
			(end 0.12065 0.2794)
			(stroke
				(width 0.1)
				(type default)
			)
			(layer "B.Fab")
		)
		(fp_line
			(start 0.12065 0.2794)
			(end 0.12065 0.3048)
			(stroke
				(width 0.1)
				(type default)
			)
			(layer "B.Fab")
		)
		(fp_line
			(start -0.12065 -0.2794)
			(end -0.12065 -0.3048)
			(stroke
				(width 0.1)
				(type default)
			)
			(layer "B.Fab")
		)
		(fp_line
			(start 0.12065 -0.2794)
			(end -0.12065 -0.2794)
			(stroke
				(width 0.1)
				(type default)
			)
			(layer "B.Fab")
		)
		(fp_line
			(start -0.67945 -0.3048)
			(end -0.67945 0.3048)
			(stroke
				(width 0.1)
				(type default)
			)
			(layer "B.Fab")
		)
		(fp_line
			(start -0.12065 -0.3048)
			(end -0.67945 -0.3048)
			(stroke
				(width 0.1)
				(type default)
			)
			(layer "B.Fab")
		)
		(fp_line
			(start 0.12065 -0.305054)
			(end 0.12065 -0.2794)
			(stroke
				(width 0.1)
				(type default)
			)
			(layer "B.Fab")
		)
		(fp_line
			(start 0.67945 -0.305054)
			(end 0.12065 -0.305054)
			(stroke
				(width 0.1)
				(type default)
			)
			(layer "B.Fab")
		)
		(pad "1" smd circle
			(at 0.40005 0 90)
			(size 0 0)
			(layers "B.Cu" "B.Mask" "B.Paste")
			(net "PVDD11_S3_P0_PMALERT")
		)
		(pad "2" smd circle
			(at -0.40005 0 90)
			(size 0 0)
			(layers "B.Cu" "B.Mask" "B.Paste")
			(net "P3V3_AUX")
		)
	)
)
